# T6G (Grand Teton) — schematic netlist excerpt (pin names and nets, part order shuffled) for the footprints in the layout excerpt that follows; sources: Cadence DE-HDL packaged netlist, KiCad conversion of 04192023_DAF0TMB3IC0_F0TG_MB_C_brd_V02_OCP.brd

J32  SCONN288_DDR506112002KQ  IO  pkg DDR288S_1-1VXC  page 102
  VIN_BULK0  = P12V_MEM_CPU1
  RFU0  = NC
  VIN_MGMT  = P3V3_AUX
  HSCL  = I3C_SPD_DDRE_CPU1_SCL
  HSDA  = I3C_SPD_DDRE_CPU1_SDA
  VSS0  = GND
  DQ0_A  = M_E_CPU1_SA_DQ<0>
  VSS1  = GND
  DQ1_A  = M_E_CPU1_SA_DQ<1>
  VSS2  = GND
  DQS0_A_T  = M_E_CPU1_SA_DQS_DP<0>
  DQS0_A_C  = M_E_CPU1_SA_DQS_DN<0>
  VSS3  = GND
  DQ4_A  = M_E_CPU1_SA_DQ<4>
  VSS4  = GND
  DQ5_A  = M_E_CPU1_SA_DQ<5>
  VSS5  = GND
  DQ8_A  = M_E_CPU1_SA_DQ<8>
  VSS6  = GND
  DQ9_A  = M_E_CPU1_SA_DQ<9>
  VSS7  = GND
  DQS1_A_T  = M_E_CPU1_SA_DQS_DP<1>
  DQS1_A_C  = M_E_CPU1_SA_DQS_DN<1>
  VSS8  = GND
  DQ12_A  = M_E_CPU1_SA_DQ<12>
  VSS9  = GND
  DQ13_A  = M_E_CPU1_SA_DQ<13>
  VSS10  = GND
  DQ16_A  = M_E_CPU1_SA_DQ<16>
  VSS11  = GND
  DQ17_A  = M_E_CPU1_SA_DQ<17>
  VSS12  = GND
  DQS2_A_T  = M_E_CPU1_SA_DQS_DP<2>
  DQS2_A_C  = M_E_CPU1_SA_DQS_DN<2>
  VSS13  = GND
  DQ20_A  = M_E_CPU1_SA_DQ<20>
  VSS14  = GND
  DQ21_A  = M_E_CPU1_SA_DQ<21>
  VSS15  = GND
  DQ24_A  = M_E_CPU1_SA_DQ<24>
  VSS16  = GND
  DQ25_A  = M_E_CPU1_SA_DQ<25>
  VSS17  = GND
  DQS3_A_T  = M_E_CPU1_SA_DQS_DP<3>
  DQS3_A_C  = M_E_CPU1_SA_DQS_DN<3>
  VSS18  = GND
  DQ28_A  = M_E_CPU1_SA_DQ<28>
  VSS19  = GND
  DQ29_A  = M_E_CPU1_SA_DQ<29>
  VSS20  = GND
  CB0_A  = M_E_CPU1_SA_CB<0>
  VSS21  = GND
  CB1_A  = M_E_CPU1_SA_CB<1>
  VSS22  = GND
  DQS4_A_T  = M_E_CPU1_SA_DQS_DP<4>
  DQS4_A_C  = M_E_CPU1_SA_DQS_DN<4>
  VSS23  = GND
  CB4_A  = M_E_CPU1_SA_CB<4>
  VSS24  = GND
  CB5_A  = M_E_CPU1_SA_CB<5>
  VSS25  = GND
  ALERT_N  = M_E_CPU1_ALERT_N
  VSS26  = GND
  CS0_A_N  = M_E_CPU1_SA_CS_N<0>
  VSS27  = GND
  CA0_A  = M_E_CPU1_SA_CA<0>
  VSS28  = GND
  CA2_A  = M_E_CPU1_SA_CA<2>
  VSS29  = GND
  CA4_A  = M_E_CPU1_SA_CA<4>
  VSS30  = GND
  CA6_A  = M_E_CPU1_SA_CA<6>
  VSS31  = GND
  PAR_A  = M_E_CPU1_SA_PAR
  VSS32  = GND
  CA0_B  = M_E_CPU1_SB_CA<0>
  VSS33  = GND
  CA2_B  = M_E_CPU1_SB_CA<2>
  VSS34  = GND
  CA4_B  = M_E_CPU1_SB_CA<4>
  VSS35  = GND
  CA6_B  = M_E_CPU1_SB_CA<6>
  VSS36  = GND
  CS0_B_N  = M_E_CPU1_SB_CS_N<0>
  VSS37  = GND
  \lbd||rsp_a_n\  = M_E_CPU1_SA_RSP<0>
  \lbs||rsp_b_n\  = M_E_CPU1_SB_RSP<0>
  VSS38  = GND
  CB4_B  = M_E_CPU1_SB_CB<4>
  VSS39  = GND
  CB5_B  = M_E_CPU1_SB_CB<5>
  VSS40  = GND
  \dqs9_b_t||tdqs9_b_t||dbi4_b_n\  = M_E_CPU1_SB_DQS_DP<9>
  \dqs9_b_c||tdqs9_b_c\  = M_E_CPU1_SB_DQS_DN<9>
  VSS41  = GND
  CB0_B  = M_E_CPU1_SB_CB<0>
  VSS42  = GND
  CB1_B  = M_E_CPU1_SB_CB<1>
  VSS43  = GND
  DQ0_B  = M_E_CPU1_SB_DQ<0>
  VSS44  = GND
  DQ1_B  = M_E_CPU1_SB_DQ<1>
  VSS45  = GND
  DQS0_B_T  = M_E_CPU1_SB_DQS_DP<0>
  DQS0_B_C  = M_E_CPU1_SB_DQS_DN<0>
  VSS46  = GND
  DQ4_B  = M_E_CPU1_SB_DQ<4>
  VSS47  = GND
  DQ5_B  = M_E_CPU1_SB_DQ<5>
  VSS48  = GND
  DQ8_B  = M_E_CPU1_SB_DQ<8>
  VSS49  = GND
  DQ9_B  = M_E_CPU1_SB_DQ<9>
  VSS50  = GND
  DQS1_B_T  = M_E_CPU1_SB_DQS_DP<1>
  DQS1_B_C  = M_E_CPU1_SB_DQS_DN<1>
  VSS51  = GND
  DQ12_B  = M_E_CPU1_SB_DQ<12>
  VSS52  = GND
  DQ13_B  = M_E_CPU1_SB_DQ<13>
  VSS53  = GND
  DQ16_B  = M_E_CPU1_SB_DQ<16>
  VSS54  = GND
  DQ17_B  = M_E_CPU1_SB_DQ<17>
  VSS55  = GND
  DQS2_B_T  = M_E_CPU1_SB_DQS_DP<2>
  DQS2_B_C  = M_E_CPU1_SB_DQS_DN<2>
  VSS56  = GND
  DQ20_B  = M_E_CPU1_SB_DQ<20>
  VSS57  = GND
  DQ21_B  = M_E_CPU1_SB_DQ<21>
  VSS58  = GND
  DQ24_B  = M_E_CPU1_SB_DQ<24>
  VSS59  = GND
  DQ25_B  = M_E_CPU1_SB_DQ<25>
  VSS60  = GND
  DQS3_B_T  = M_E_CPU1_SB_DQS_DP<3>
  DQS3_B_C  = M_E_CPU1_SB_DQS_DN<3>
  VSS61  = GND
  DQ28_B  = M_E_CPU1_SB_DQ<28>
  VSS62  = GND
  DQ29_B  = M_E_CPU1_SB_DQ<29>
  VSS63  = GND
  RFU1  = NC
  VIN_BULK1  = P12V_MEM_CPU1
  VIN_BULK2  = P12V_MEM_CPU1
  \pwr_good||fail_n\  = PWRGD_CHE_CPU1_DIMM
  HAS  = PD_CHE_CPU1_DIMM_SAA
  RFU2  = NC
  RFU3  = NC
  VSS64  = GND
  DQ2_A  = M_E_CPU1_SA_DQ<2>
  VSS65  = GND
  DQ3_A  = M_E_CPU1_SA_DQ<3>
  VSS66  = GND
  \dqs5_a_c||tdqs5_a_c||dqs5_a_t||tdqs5_a_t\  = M_E_CPU1_SA_DQS_DN<5>
  \dqs5_a_t||tdqs5_a_t\  = M_E_CPU1_SA_DQS_DP<5>
  VSS67  = GND
  DQ6_A  = M_E_CPU1_SA_DQ<6>
  VSS68  = GND
  DQ7_A  = M_E_CPU1_SA_DQ<7>
  VSS69  = GND
  DQ10_A  = M_E_CPU1_SA_DQ<10>
  VSS70  = GND
  DQ11_A  = M_E_CPU1_SA_DQ<11>
  VSS71  = GND
  \dqs6_a_c||tdqs6_a_c||dqs6_a_t||tdqs6_a_t\  = M_E_CPU1_SA_DQS_DN<6>
  \dqs6_a_t||tdqs6_a_t\  = M_E_CPU1_SA_DQS_DP<6>
  VSS72  = GND
  DQ14_A  = M_E_CPU1_SA_DQ<14>
  VSS73  = GND
  DQ15_A  = M_E_CPU1_SA_DQ<15>
  VSS74  = GND
  DQ18_A  = M_E_CPU1_SA_DQ<18>
  VSS75  = GND
  DQ19_A  = M_E_CPU1_SA_DQ<19>
  VSS76  = GND
  \dqs7_a_c||tdqs7_a_c\  = M_E_CPU1_SA_DQS_DN<7>
  \dqs7_a_t||tdqs7_a_t\  = M_E_CPU1_SA_DQS_DP<7>
  VSS77  = GND
  DQ22_A  = M_E_CPU1_SA_DQ<22>
  VSS78  = GND
  DQ23_A  = M_E_CPU1_SA_DQ<23>
  VSS79  = GND
  DQ26_A  = M_E_CPU1_SA_DQ<26>
  VSS80  = GND
  DQ27_A  = M_E_CPU1_SA_DQ<27>
  VSS81  = GND
  \dqs8_a_c||tdqs8_a_c\  = M_E_CPU1_SA_DQS_DN<8>
  \dqs8_a_t||tdqs8_a_t\  = M_E_CPU1_SA_DQS_DP<8>
  VSS82  = GND
  DQ30_A  = M_E_CPU1_SA_DQ<30>
  VSS83  = GND
  DQ31_A  = M_E_CPU1_SA_DQ<31>
  VSS84  = GND
  CB2_A  = M_E_CPU1_SA_CB<2>
  VSS85  = GND
  CB3_A  = M_E_CPU1_SA_CB<3>
  VSS86  = GND
  \dqs9_a_c||tdqs9_a_c\  = M_E_CPU1_SA_DQS_DN<9>
  \dqs9_a_t||tdqs9_a_t\  = M_E_CPU1_SA_DQS_DP<9>
  VSS87  = GND
  CB6_A  = M_E_CPU1_SA_CB<6>
  VSS88  = GND
  CB7_A  = M_E_CPU1_SA_CB<7>
  VSS89  = GND
  RESET_N  = M_E_CPU1_RESET_N
  VSS90  = GND
  CS1_A_N  = M_E_CPU1_SA_CS_N<1>
  VSS91  = GND
  CA1_A  = M_E_CPU1_SA_CA<1>
  VSS92  = GND
  CA3_A  = M_E_CPU1_SA_CA<3>
  VSS93  = GND
  CA5_A  = M_E_CPU1_SA_CA<5>
  VSS94  = GND
  CK_T  = M_E_CPU1_CLK_DP<0>
  CK_C  = M_E_CPU1_CLK_DN<0>
  VSS95  = GND
  RFU4  = NC
  CA1_B  = M_E_CPU1_SB_CA<1>
  VSS96  = GND
  CA3_B  = M_E_CPU1_SB_CA<3>
  VSS97  = GND
  CA5_B  = M_E_CPU1_SB_CA<5>
  VSS98  = GND
  PAR_B  = M_E_CPU1_SB_PAR
  VSS99  = GND
  CS1_B_N  = M_E_CPU1_SB_CS_N<1>
  VSS100  = GND
  RFU5  = NC
  RFU6  = NC
  VSS101  = GND
  CB6_B  = M_E_CPU1_SB_CB<6>
  VSS102  = GND
  CB7_B  = M_E_CPU1_SB_CB<7>
  VSS103  = GND
  DQS4_B_C  = M_E_CPU1_SB_DQS_DN<4>
  DQS4_B_T  = M_E_CPU1_SB_DQS_DP<4>
  VSS104  = GND
  CB2_B  = M_E_CPU1_SB_CB<2>
  VSS105  = GND
  CB3_B  = M_E_CPU1_SB_CB<3>
  VSS106  = GND
  DQ2_B  = M_E_CPU1_SB_DQ<2>
  VSS107  = GND
  DQ3_B  = M_E_CPU1_SB_DQ<3>
  VSS108  = GND
  \dqs5_b_c||tdqs5_b_c\  = M_E_CPU1_SB_DQS_DN<5>
  \dqs5_b_t||tdqs5_b_t\  = M_E_CPU1_SB_DQS_DP<5>
  VSS109  = GND
  DQ6_B  = M_E_CPU1_SB_DQ<6>
  VSS110  = GND
  DQ7_B  = M_E_CPU1_SB_DQ<7>
  VSS111  = GND
  DQ10_B  = M_E_CPU1_SB_DQ<10>
  VSS112  = GND
  DQ11_B  = M_E_CPU1_SB_DQ<11>
  VSS113  = GND
  \dqs6_b_c||tdqs6_b_c\  = M_E_CPU1_SB_DQS_DN<6>
  \dqs6_b_t||tdqs6_b_t\  = M_E_CPU1_SB_DQS_DP<6>
  VSS114  = GND
  DQ14_B  = M_E_CPU1_SB_DQ<14>
  VSS115  = GND
  DQ15_B  = M_E_CPU1_SB_DQ<15>
  VSS116  = GND
  DQ18_B  = M_E_CPU1_SB_DQ<18>
  VSS117  = GND
  DQ19_B  = M_E_CPU1_SB_DQ<19>
  VSS118  = GND
  \dqs7_b_c||tdqs7_b_c\  = M_E_CPU1_SB_DQS_DN<7>
  \dqs7_b_t||tdqs7_b_t\  = M_E_CPU1_SB_DQS_DP<7>
  VSS119  = GND
  DQ22_B  = M_E_CPU1_SB_DQ<22>
  VSS120  = GND
  DQ23_B  = M_E_CPU1_SB_DQ<23>
  VSS121  = GND
  DQ26_B  = M_E_CPU1_SB_DQ<26>
  VSS122  = GND
  DQ27_B  = M_E_CPU1_SB_DQ<27>
  VSS123  = GND
  \dqs8_b_c||tdqs8_b_c\  = M_E_CPU1_SB_DQS_DN<8>
  \dqs8_b_t||tdqs8_b_t\  = M_E_CPU1_SB_DQS_DP<8>
  VSS124  = GND
  DQ30_B  = M_E_CPU1_SB_DQ<30>
  VSS125  = GND
  DQ31_B  = M_E_CPU1_SB_DQ<31>
  VSS126  = GND
  G1  = GND
  G2  = GND
  G3  = GND

(kicad_pcb
	(version 20260206)
	(generator "pcbnew")
	(generator_version "10.0")
	(general
		(thickness 1.6)
		(legacy_teardrops no)
	)
	(paper "A4")
	(title_block
		(title "04192023_DAF0TMB3IC0_F0TG_MB_C_brd_V02_OCP.brd")
		(comment 1 "Grand Teton / footprint 4612 of 8354 (J32), pads 47-92 of 291")
	)
	(layers
		(0 "F.Cu" signal "TOP")
		(4 "In1.Cu" signal "GND")
		(6 "In2.Cu" signal "IN1")
		(8 "In3.Cu" signal "GND1")
		(10 "In4.Cu" signal "IN2")
		(12 "In5.Cu" signal "GND2")
		(14 "In6.Cu" signal "IN3")
		(16 "In7.Cu" signal "GND3")
		(18 "In8.Cu" signal "VCC")
		(20 "In9.Cu" signal "VCC1")
		(22 "In10.Cu" signal "GND4")
		(24 "In11.Cu" signal "IN4")
		(26 "In12.Cu" signal "GND5")
		(28 "In13.Cu" signal "IN5")
		(30 "In14.Cu" signal "GND6")
		(32 "In15.Cu" signal "IN6")
		(34 "In16.Cu" signal "GND7")
		(2 "B.Cu" signal "BOTTOM")
		(9 "F.Adhes" user "F.Adhesive")
		(11 "B.Adhes" user "B.Adhesive")
		(13 "F.Paste" user "Package Geometry/Pastemask Top")
		(15 "B.Paste" user "Package Geometry/Pastemask Bottom")
		(5 "F.SilkS" user "Ref Des/Silkscreen Top")
		(7 "B.SilkS" user "Ref Des/Silkscreen Bottom")
		(1 "F.Mask" user "Board Geometry/Soldermask Top")
		(3 "B.Mask" user "Board Geometry/Soldermask Bottom")
		(17 "Dwgs.User" user "User.Drawings")
		(19 "Cmts.User" user "User.Comments")
		(21 "Eco1.User" user "User.Eco1")
		(23 "Eco2.User" user "User.Eco2")
		(25 "Edge.Cuts" user "Board Geometry/Outline")
		(27 "Margin" user)
		(31 "F.CrtYd" user "Package Geometry/Place Bound Top")
		(29 "B.CrtYd" user "Package Geometry/Place Bound Bottom")
		(35 "F.Fab" user "Ref Des/Assembly Top")
		(33 "B.Fab" user "Ref Des/Assembly Bottom")
	)
	(footprint ""
		(layer "F.Cu")
		(at 27.20213 -255.560322 180)
		(property "Reference" "J32"
			(at 1.80086 -81.974436 0)
			(unlocked yes)
			(layer "F.SilkS")
			(effects
				(font
					(size 0.7874 0.5842)
					(thickness 0.1524)
				)
			)
		)
		(property "Value" ""
			(at 0 0 180)
			(layer "F.Fab")
			(effects
				(font
					(size 1.27 1.27)
				)
			)
		)
		(duplicate_pad_numbers_are_jumpers no)
		(pad "47" smd rect
			(at -2.050034 -24.224996 90)
			(size 0.519938 1.4986)
			(layers "F.Cu" "F.Mask" "F.Paste")
			(net "M_E_CPU1_SA_DQ<28>")
		)
		(pad "48" smd rect
			(at -2.050034 -23.375112 90)
			(size 0.519938 1.4986)
			(layers "F.Cu" "F.Mask" "F.Paste")
			(net "GND")
		)
		(pad "49" smd rect
			(at -2.050034 -22.524974 90)
			(size 0.519938 1.4986)
			(layers "F.Cu" "F.Mask" "F.Paste")
			(net "M_E_CPU1_SA_DQ<29>")
		)
		(pad "50" smd rect
			(at -2.050034 -21.67509 90)
			(size 0.519938 1.4986)
			(layers "F.Cu" "F.Mask" "F.Paste")
			(net "GND")
		)
		(pad "51" smd rect
			(at -2.050034 -20.824952 90)
			(size 0.519938 1.4986)
			(layers "F.Cu" "F.Mask" "F.Paste")
			(net "M_E_CPU1_SA_CB<0>")
		)
		(pad "52" smd rect
			(at -2.050034 -19.975068 90)
			(size 0.519938 1.4986)
			(layers "F.Cu" "F.Mask" "F.Paste")
			(net "GND")
		)
		(pad "53" smd rect
			(at -2.050034 -19.12493 90)
			(size 0.519938 1.4986)
			(layers "F.Cu" "F.Mask" "F.Paste")
			(net "M_E_CPU1_SA_CB<1>")
		)
		(pad "54" smd rect
			(at -2.050034 -18.275046 90)
			(size 0.519938 1.4986)
			(layers "F.Cu" "F.Mask" "F.Paste")
			(net "GND")
		)
		(pad "55" smd rect
			(at -2.050034 -17.424908 90)
			(size 0.519938 1.4986)
			(layers "F.Cu" "F.Mask" "F.Paste")
			(net "M_E_CPU1_SA_DQS_DP<4>")
		)
		(pad "56" smd rect
			(at -2.050034 -16.575024 90)
			(size 0.519938 1.4986)
			(layers "F.Cu" "F.Mask" "F.Paste")
			(net "M_E_CPU1_SA_DQS_DN<4>")
		)
		(pad "57" smd rect
			(at -2.050034 -15.724886 90)
			(size 0.519938 1.4986)
			(layers "F.Cu" "F.Mask" "F.Paste")
			(net "GND")
		)
		(pad "58" smd rect
			(at -2.050034 -14.875002 90)
			(size 0.519938 1.4986)
			(layers "F.Cu" "F.Mask" "F.Paste")
			(net "M_E_CPU1_SA_CB<4>")
		)
		(pad "59" smd rect
			(at -2.050034 -14.025118 90)
			(size 0.519938 1.4986)
			(layers "F.Cu" "F.Mask" "F.Paste")
			(net "GND")
		)
		(pad "60" smd rect
			(at -2.050034 -13.17498 90)
			(size 0.519938 1.4986)
			(layers "F.Cu" "F.Mask" "F.Paste")
			(net "M_E_CPU1_SA_CB<5>")
		)
		(pad "61" smd rect
			(at -2.050034 -12.325096 90)
			(size 0.519938 1.4986)
			(layers "F.Cu" "F.Mask" "F.Paste")
			(net "GND")
		)
		(pad "62" smd rect
			(at -2.050034 -11.474958 90)
			(size 0.519938 1.4986)
			(layers "F.Cu" "F.Mask" "F.Paste")
			(net "M_E_CPU1_ALERT_N")
		)
		(pad "63" smd rect
			(at -2.050034 -10.625074 90)
			(size 0.519938 1.4986)
			(layers "F.Cu" "F.Mask" "F.Paste")
			(net "GND")
		)
		(pad "64" smd rect
			(at -2.050034 -9.774936 90)
			(size 0.519938 1.4986)
			(layers "F.Cu" "F.Mask" "F.Paste")
			(net "M_E_CPU1_SA_CS_N<0>")
		)
		(pad "65" smd rect
			(at -2.050034 -8.925052 90)
			(size 0.519938 1.4986)
			(layers "F.Cu" "F.Mask" "F.Paste")
			(net "GND")
		)
		(pad "66" smd rect
			(at -2.050034 -8.074914 90)
			(size 0.519938 1.4986)
			(layers "F.Cu" "F.Mask" "F.Paste")
			(net "M_E_CPU1_SA_CA<0>")
		)
		(pad "67" smd rect
			(at -2.050034 -7.22503 90)
			(size 0.519938 1.4986)
			(layers "F.Cu" "F.Mask" "F.Paste")
			(net "GND")
		)
		(pad "68" smd rect
			(at -2.050034 -6.374892 90)
			(size 0.519938 1.4986)
			(layers "F.Cu" "F.Mask" "F.Paste")
			(net "M_E_CPU1_SA_CA<2>")
		)
		(pad "69" smd rect
			(at -2.050034 -5.525008 90)
			(size 0.519938 1.4986)
			(layers "F.Cu" "F.Mask" "F.Paste")
			(net "GND")
		)
		(pad "70" smd rect
			(at -2.050034 -4.675124 90)
			(size 0.519938 1.4986)
			(layers "F.Cu" "F.Mask" "F.Paste")
			(net "M_E_CPU1_SA_CA<4>")
		)
		(pad "71" smd rect
			(at -2.050034 -3.824986 90)
			(size 0.519938 1.4986)
			(layers "F.Cu" "F.Mask" "F.Paste")
			(net "GND")
		)
		(pad "72" smd rect
			(at -2.050034 -2.975102 90)
			(size 0.519938 1.4986)
			(layers "F.Cu" "F.Mask" "F.Paste")
			(net "M_E_CPU1_SA_CA<6>")
		)
		(pad "73" smd rect
			(at -2.050034 -2.124964 90)
			(size 0.519938 1.4986)
			(layers "F.Cu" "F.Mask" "F.Paste")
			(net "GND")
		)
		(pad "74" smd rect
			(at -2.050034 -1.27508 90)
			(size 0.519938 1.4986)
			(layers "F.Cu" "F.Mask" "F.Paste")
			(net "M_E_CPU1_SA_PAR")
		)
		(pad "75" smd rect
			(at -2.050034 -0.424942 90)
			(size 0.519938 1.4986)
			(layers "F.Cu" "F.Mask" "F.Paste")
			(net "GND")
		)
		(pad "76" smd rect
			(at -2.050034 5.525008 90)
			(size 0.519938 1.4986)
			(layers "F.Cu" "F.Mask" "F.Paste")
			(net "M_E_CPU1_SB_CA<0>")
		)
		(pad "77" smd rect
			(at -2.050034 6.374892 90)
			(size 0.519938 1.4986)
			(layers "F.Cu" "F.Mask" "F.Paste")
			(net "GND")
		)
		(pad "78" smd rect
			(at -2.050034 7.22503 90)
			(size 0.519938 1.4986)
			(layers "F.Cu" "F.Mask" "F.Paste")
			(net "M_E_CPU1_SB_CA<2>")
		)
		(pad "79" smd rect
			(at -2.050034 8.074914 90)
			(size 0.519938 1.4986)
			(layers "F.Cu" "F.Mask" "F.Paste")
			(net "GND")
		)
		(pad "80" smd rect
			(at -2.050034 8.925052 90)
			(size 0.519938 1.4986)
			(layers "F.Cu" "F.Mask" "F.Paste")
			(net "M_E_CPU1_SB_CA<4>")
		)
		(pad "81" smd rect
			(at -2.050034 9.774936 90)
			(size 0.519938 1.4986)
			(layers "F.Cu" "F.Mask" "F.Paste")
			(net "GND")
		)
		(pad "82" smd rect
			(at -2.050034 10.625074 90)
			(size 0.519938 1.4986)
			(layers "F.Cu" "F.Mask" "F.Paste")
			(net "M_E_CPU1_SB_CA<6>")
		)
		(pad "83" smd rect
			(at -2.050034 11.474958 90)
			(size 0.519938 1.4986)
			(layers "F.Cu" "F.Mask" "F.Paste")
			(net "GND")
		)
		(pad "84" smd rect
			(at -2.050034 12.325096 90)
			(size 0.519938 1.4986)
			(layers "F.Cu" "F.Mask" "F.Paste")
			(net "M_E_CPU1_SB_CS_N<0>")
		)
		(pad "85" smd rect
			(at -2.050034 13.17498 90)
			(size 0.519938 1.4986)
			(layers "F.Cu" "F.Mask" "F.Paste")
			(net "GND")
		)
		(pad "86" smd rect
			(at -2.050034 14.025118 90)
			(size 0.519938 1.4986)
			(layers "F.Cu" "F.Mask" "F.Paste")
			(net "M_E_CPU1_SA_RSP<0>")
		)
		(pad "87" smd rect
			(at -2.050034 14.875002 90)
			(size 0.519938 1.4986)
			(layers "F.Cu" "F.Mask" "F.Paste")
			(net "M_E_CPU1_SB_RSP<0>")
		)
		(pad "88" smd rect
			(at -2.050034 15.724886 90)
			(size 0.519938 1.4986)
			(layers "F.Cu" "F.Mask" "F.Paste")
			(net "GND")
		)
		(pad "89" smd rect
			(at -2.050034 16.575024 90)
			(size 0.519938 1.4986)
			(layers "F.Cu" "F.Mask" "F.Paste")
			(net "M_E_CPU1_SB_CB<4>")
		)
		(pad "90" smd rect
			(at -2.050034 17.424908 90)
			(size 0.519938 1.4986)
			(layers "F.Cu" "F.Mask" "F.Paste")
			(net "GND")
		)
		(pad "91" smd rect
			(at -2.050034 18.275046 90)
			(size 0.519938 1.4986)
			(layers "F.Cu" "F.Mask" "F.Paste")
			(net "M_E_CPU1_SB_CB<5>")
		)
		(pad "92" smd rect
			(at -2.050034 19.12493 90)
			(size 0.519938 1.4986)
			(layers "F.Cu" "F.Mask" "F.Paste")
			(net "GND")
		)
	)
)
